# T6G (Grand Teton) — schematic netlist excerpt (pin names and nets, part order shuffled) for the footprints in the layout excerpt that follows; sources: Cadence DE-HDL packaged netlist, KiCad conversion of 04192023_DAF0TMB3IC0_F0TG_MB_C_brd_V02_OCP.brd

R6242  Q_RES  0 5% CHIP  pkg 0402LF  page 269 : A = P3V3_AUX ; B = P1V8_AUX_VCC
R5103  Q_RES  49.9 1% CHIP  pkg 0402LF  page 55 : A = XTAL_CPU1_X48M_X2 ; B = XTAL_CPU1_X48M_X2_R
C6747  Q_CAP_DIFFBUS  DIFF BUS_0.22UF 6.3V 20% X6S  pkg C0201  page 352 : \1\ = P5E_CPU1_P3_TX_BUF_C_DP<11> ; \2\ = P5E_CPU1_P3_TX_BUF_DP<11>

(kicad_pcb
	(version 20260206)
	(generator "pcbnew")
	(generator_version "10.0")
	(general
		(thickness 1.6)
		(legacy_teardrops no)
	)
	(paper "A4")
	(title_block
		(title "04192023_DAF0TMB3IC0_F0TG_MB_C_brd_V02_OCP.brd")
		(comment 1 "Grand Teton / footprints 6655-6657 of 8354")
	)
	(layers
		(0 "F.Cu" signal "TOP")
		(4 "In1.Cu" signal "GND")
		(6 "In2.Cu" signal "IN1")
		(8 "In3.Cu" signal "GND1")
		(10 "In4.Cu" signal "IN2")
		(12 "In5.Cu" signal "GND2")
		(14 "In6.Cu" signal "IN3")
		(16 "In7.Cu" signal "GND3")
		(18 "In8.Cu" signal "VCC")
		(20 "In9.Cu" signal "VCC1")
		(22 "In10.Cu" signal "GND4")
		(24 "In11.Cu" signal "IN4")
		(26 "In12.Cu" signal "GND5")
		(28 "In13.Cu" signal "IN5")
		(30 "In14.Cu" signal "GND6")
		(32 "In15.Cu" signal "IN6")
		(34 "In16.Cu" signal "GND7")
		(2 "B.Cu" signal "BOTTOM")
		(9 "F.Adhes" user "F.Adhesive")
		(11 "B.Adhes" user "B.Adhesive")
		(13 "F.Paste" user "Package Geometry/Pastemask Top")
		(15 "B.Paste" user "Package Geometry/Pastemask Bottom")
		(5 "F.SilkS" user "Ref Des/Silkscreen Top")
		(7 "B.SilkS" user "Ref Des/Silkscreen Bottom")
		(1 "F.Mask" user "Board Geometry/Soldermask Top")
		(3 "B.Mask" user "Board Geometry/Soldermask Bottom")
		(17 "Dwgs.User" user "User.Drawings")
		(19 "Cmts.User" user "User.Comments")
		(21 "Eco1.User" user "User.Eco1")
		(23 "Eco2.User" user "User.Eco2")
		(25 "Edge.Cuts" user "Board Geometry/Outline")
		(27 "Margin" user)
		(31 "F.CrtYd" user "Package Geometry/Place Bound Top")
		(29 "B.CrtYd" user "Package Geometry/Place Bound Bottom")
		(35 "F.Fab" user "Ref Des/Assembly Top")
		(33 "B.Fab" user "Ref Des/Assembly Bottom")
	)
	(footprint ""
		(layer "B.Cu")
		(at 143.401542 -81.786222)
		(property "Reference" "R6242"
			(at 0 0 0)
			(layer "B.SilkS")
			(hide yes)
			(effects
				(font
					(size 1.27 1.27)
				)
				(justify mirror)
			)
		)
		(property "Value" ""
			(at 0 0 0)
			(layer "B.Fab")
			(effects
				(font
					(size 1.27 1.27)
				)
				(justify mirror)
			)
		)
		(duplicate_pad_numbers_are_jumpers no)
		(fp_line
			(start -0.7874 -0.4064)
			(end -0.7874 0.4064)
			(stroke
				(width 0.1524)
				(type default)
			)
			(layer "B.SilkS")
		)
		(fp_line
			(start -0.7874 0.4064)
			(end 0.7874 0.4064)
			(stroke
				(width 0.1524)
				(type default)
			)
			(layer "B.SilkS")
		)
		(fp_line
			(start 0.7874 -0.4064)
			(end -0.7874 -0.4064)
			(stroke
				(width 0.1524)
				(type default)
			)
			(layer "B.SilkS")
		)
		(fp_line
			(start 0.7874 0.4064)
			(end 0.7874 -0.4064)
			(stroke
				(width 0.1524)
				(type default)
			)
			(layer "B.SilkS")
		)
		(fp_line
			(start -0.67945 -0.3048)
			(end -0.67945 0.3048)
			(stroke
				(width 0.1)
				(type default)
			)
			(layer "B.Fab")
		)
		(fp_line
			(start -0.67945 0.3048)
			(end -0.120396 0.3048)
			(stroke
				(width 0.1)
				(type default)
			)
			(layer "B.Fab")
		)
		(fp_line
			(start -0.12065 -0.3048)
			(end -0.67945 -0.3048)
			(stroke
				(width 0.1)
				(type default)
			)
			(layer "B.Fab")
		)
		(fp_line
			(start -0.12065 -0.2794)
			(end -0.12065 -0.3048)
			(stroke
				(width 0.1)
				(type default)
			)
			(layer "B.Fab")
		)
		(fp_line
			(start -0.120396 0.2794)
			(end 0.12065 0.2794)
			(stroke
				(width 0.1)
				(type default)
			)
			(layer "B.Fab")
		)
		(fp_line
			(start -0.120396 0.3048)
			(end -0.120396 0.2794)
			(stroke
				(width 0.1)
				(type default)
			)
			(layer "B.Fab")
		)
		(fp_line
			(start 0.12065 -0.305054)
			(end 0.12065 -0.2794)
			(stroke
				(width 0.1)
				(type default)
			)
			(layer "B.Fab")
		)
		(fp_line
			(start 0.12065 -0.2794)
			(end -0.12065 -0.2794)
			(stroke
				(width 0.1)
				(type default)
			)
			(layer "B.Fab")
		)
		(fp_line
			(start 0.12065 0.2794)
			(end 0.12065 0.3048)
			(stroke
				(width 0.1)
				(type default)
			)
			(layer "B.Fab")
		)
		(fp_line
			(start 0.12065 0.3048)
			(end 0.67945 0.3048)
			(stroke
				(width 0.1)
				(type default)
			)
			(layer "B.Fab")
		)
		(fp_line
			(start 0.67945 -0.305054)
			(end 0.12065 -0.305054)
			(stroke
				(width 0.1)
				(type default)
			)
			(layer "B.Fab")
		)
		(fp_line
			(start 0.67945 0.3048)
			(end 0.67945 -0.305054)
			(stroke
				(width 0.1)
				(type default)
			)
			(layer "B.Fab")
		)
		(pad "1" smd circle
			(at 0.40005 0 180)
			(size 0 0)
			(layers "B.Cu" "B.Mask" "B.Paste")
			(net "P3V3_AUX")
		)
		(pad "2" smd circle
			(at -0.40005 0 180)
			(size 0 0)
			(layers "B.Cu" "B.Mask" "B.Paste")
			(net "P1V8_AUX_VCC")
		)
	)
	(footprint ""
		(layer "B.Cu")
		(at 151.010366 -408.517344 90)
		(property "Reference" "C6747"
			(at 0 0 90)
			(layer "B.SilkS")
			(hide yes)
			(effects
				(font
					(size 1.27 1.27)
				)
				(justify mirror)
			)
		)
		(property "Value" ""
			(at 0 0 90)
			(layer "B.Fab")
			(effects
				(font
					(size 1.27 1.27)
				)
				(justify mirror)
			)
		)
		(duplicate_pad_numbers_are_jumpers no)
		(fp_line
			(start 0.299974 -0.150114)
			(end -0.299974 -0.150114)
			(stroke
				(width 0.1)
				(type default)
			)
			(layer "B.Fab")
		)
		(fp_line
			(start -0.299974 -0.150114)
			(end -0.299974 0.150114)
			(stroke
				(width 0.1)
				(type default)
			)
			(layer "B.Fab")
		)
		(fp_line
			(start 0.299974 0.150114)
			(end 0.299974 -0.150114)
			(stroke
				(width 0.1)
				(type default)
			)
			(layer "B.Fab")
		)
		(fp_line
			(start -0.299974 0.150114)
			(end 0.299974 0.150114)
			(stroke
				(width 0.1)
				(type default)
			)
			(layer "B.Fab")
		)
		(pad "1" smd rect
			(at 0.2667 0 270)
			(size 0.3048 0.381)
			(layers "B.Cu" "B.Mask" "B.Paste")
			(net "P5E_CPU1_P3_TX_BUF_C_DP<11>")
		)
		(pad "2" smd rect
			(at -0.2667 0 270)
			(size 0.3048 0.381)
			(layers "B.Cu" "B.Mask" "B.Paste")
			(net "P5E_CPU1_P3_TX_BUF_DP<11>")
		)
	)
	(footprint ""
		(layer "B.Cu")
		(at 149.900386 -313.45505)
		(property "Reference" "R5103"
			(at 0 0 0)
			(layer "B.SilkS")
			(hide yes)
			(effects
				(font
					(size 1.27 1.27)
				)
				(justify mirror)
			)
		)
		(property "Value" ""
			(at 0 0 0)
			(layer "B.Fab")
			(effects
				(font
					(size 1.27 1.27)
				)
				(justify mirror)
			)
		)
		(duplicate_pad_numbers_are_jumpers no)
		(fp_line
			(start -0.7874 -0.4064)
			(end -0.7874 0.4064)
			(stroke
				(width 0.1524)
				(type default)
			)
			(layer "B.SilkS")
		)
		(fp_line
			(start -0.7874 0.4064)
			(end 0.7874 0.4064)
			(stroke
				(width 0.1524)
				(type default)
			)
			(layer "B.SilkS")
		)
		(fp_line
			(start 0.7874 -0.4064)
			(end -0.7874 -0.4064)
			(stroke
				(width 0.1524)
				(type default)
			)
			(layer "B.SilkS")
		)
		(fp_line
			(start 0.7874 0.4064)
			(end 0.7874 -0.4064)
			(stroke
				(width 0.1524)
				(type default)
			)
			(layer "B.SilkS")
		)
		(fp_line
			(start -0.67945 -0.3048)
			(end -0.67945 0.3048)
			(stroke
				(width 0.1)
				(type default)
			)
			(layer "B.Fab")
		)
		(fp_line
			(start -0.67945 0.3048)
			(end -0.120396 0.3048)
			(stroke
				(width 0.1)
				(type default)
			)
			(layer "B.Fab")
		)
		(fp_line
			(start -0.12065 -0.3048)
			(end -0.67945 -0.3048)
			(stroke
				(width 0.1)
				(type default)
			)
			(layer "B.Fab")
		)
		(fp_line
			(start -0.12065 -0.2794)
			(end -0.12065 -0.3048)
			(stroke
				(width 0.1)
				(type default)
			)
			(layer "B.Fab")
		)
		(fp_line
			(start -0.120396 0.2794)
			(end 0.12065 0.2794)
			(stroke
				(width 0.1)
				(type default)
			)
			(layer "B.Fab")
		)
		(fp_line
			(start -0.120396 0.3048)
			(end -0.120396 0.2794)
			(stroke
				(width 0.1)
				(type default)
			)
			(layer "B.Fab")
		)
		(fp_line
			(start 0.12065 -0.305054)
			(end 0.12065 -0.2794)
			(stroke
				(width 0.1)
				(type default)
			)
			(layer "B.Fab")
		)
		(fp_line
			(start 0.12065 -0.2794)
			(end -0.12065 -0.2794)
			(stroke
				(width 0.1)
				(type default)
			)
			(layer "B.Fab")
		)
		(fp_line
			(start 0.12065 0.2794)
			(end 0.12065 0.3048)
			(stroke
				(width 0.1)
				(type default)
			)
			(layer "B.Fab")
		)
		(fp_line
			(start 0.12065 0.3048)
			(end 0.67945 0.3048)
			(stroke
				(width 0.1)
				(type default)
			)
			(layer "B.Fab")
		)
		(fp_line
			(start 0.67945 -0.305054)
			(end 0.12065 -0.305054)
			(stroke
				(width 0.1)
				(type default)
			)
			(layer "B.Fab")
		)
		(fp_line
			(start 0.67945 0.3048)
			(end 0.67945 -0.305054)
			(stroke
				(width 0.1)
				(type default)
			)
			(layer "B.Fab")
		)
		(pad "1" smd circle
			(at 0.40005 0 180)
			(size 0 0)
			(layers "B.Cu" "B.Mask" "B.Paste")
			(net "XTAL_CPU1_X48M_X2")
		)
		(pad "2" smd circle
			(at -0.40005 0 180)
			(size 0 0)
			(layers "B.Cu" "B.Mask" "B.Paste")
			(net "XTAL_CPU1_X48M_X2_R")
		)
	)
)
